(kicad_pcb
	(version 20260206)
	(generator "pcbnew")
	(generator_version "10.0")
	(general
		(thickness 1.6)
		(legacy_teardrops no)
	)
	(paper "A4")
	(title_block
		(title "Wiwynn_Tioga_Pass_MB.brd")
		(comment 1 "Tioga Pass / footprints 4093-4099 of 4770")
	)
	(layers
		(0 "F.Cu" signal "TOP")
		(4 "In1.Cu" signal "L2GND")
		(6 "In2.Cu" signal "L3")
		(8 "In3.Cu" signal "L4GND")
		(10 "In4.Cu" signal "L5")
		(12 "In5.Cu" signal "L6GND")
		(14 "In6.Cu" signal "L7VCC")
		(16 "In7.Cu" signal "L8VCC")
		(18 "In8.Cu" signal "L9GND")
		(20 "In9.Cu" signal "L10")
		(22 "In10.Cu" signal "L11GND")
		(24 "In11.Cu" signal "L12")
		(26 "In12.Cu" signal "L13GND")
		(2 "B.Cu" signal "BOTTOM")
		(9 "F.Adhes" user "F.Adhesive")
		(11 "B.Adhes" user "B.Adhesive")
		(13 "F.Paste" user "Package Geometry/Pastemask Top")
		(15 "B.Paste" user "Package Geometry/Pastemask Bottom")
		(5 "F.SilkS" user "Ref Des/Silkscreen Top")
		(7 "B.SilkS" user "Ref Des/Silkscreen Bottom")
		(1 "F.Mask" user "Board Geometry/Soldermask Top")
		(3 "B.Mask" user "Board Geometry/Soldermask Bottom")
		(17 "Dwgs.User" user "User.Drawings")
		(19 "Cmts.User" user "User.Comments")
		(21 "Eco1.User" user "User.Eco1")
		(23 "Eco2.User" user "User.Eco2")
		(25 "Edge.Cuts" user "Board Geometry/Outline")
		(27 "Margin" user)
		(31 "F.CrtYd" user "Package Geometry/Place Bound Top")
		(29 "B.CrtYd" user "Package Geometry/Place Bound Bottom")
		(35 "F.Fab" user "Ref Des/Assembly Top")
		(33 "B.Fab" user "Ref Des/Assembly Bottom")
	)
	(footprint ""
		(layer "B.Cu")
		(at 176.276 -20.193)
		(property "Reference" "R6T5"
			(at 0 0 0)
			(layer "B.SilkS")
			(hide yes)
			(effects
				(font
					(size 1.27 1.27)
				)
				(justify mirror)
			)
		)
		(property "Value" ""
			(at 0 0 0)
			(layer "B.Fab")
			(effects
				(font
					(size 1.27 1.27)
				)
				(justify mirror)
			)
		)
		(duplicate_pad_numbers_are_jumpers no)
		(fp_poly
			(pts
				(xy 0.2794 -0.1016) (xy -0.2794 -0.1016) (xy -0.2794 0.9906) (xy 0.2794 0.9906)
			)
			(stroke
				(width 0)
				(type default)
			)
			(fill no)
			(layer "B.CrtYd")
		)
		(fp_line
			(start -0.2794 -0.1016)
			(end 0.2794 -0.1016)
			(stroke
				(width 0.1)
				(type default)
			)
			(layer "B.Fab")
		)
		(fp_line
			(start -0.2794 0.9906)
			(end -0.2794 -0.1016)
			(stroke
				(width 0.1)
				(type default)
			)
			(layer "B.Fab")
		)
		(fp_line
			(start 0.2794 -0.1016)
			(end 0.2794 0.9906)
			(stroke
				(width 0.1)
				(type default)
			)
			(layer "B.Fab")
		)
		(fp_line
			(start 0.2794 0.9906)
			(end -0.2794 0.9906)
			(stroke
				(width 0.1)
				(type default)
			)
			(layer "B.Fab")
		)
		(pad "1" smd rect
			(at 0 0 180)
			(size 0.508 0.508)
			(layers "B.Cu" "B.Mask" "B.Paste")
			(net "XDP_CPU_TRST_N")
		)
		(pad "2" smd rect
			(at 0 0.889 180)
			(size 0.508 0.508)
			(layers "B.Cu" "B.Mask" "B.Paste")
			(net "GND")
		)
		(zone
			(layer "B.Cu")
			(hatch none 0.5)
			(connect_pads
				(clearance 0)
			)
			(min_thickness 0.25)
			(keepout
				(tracks allowed)
				(vias not_allowed)
				(pads allowed)
				(copperpour not_allowed)
				(footprints allowed)
			)
			(placement
				(enabled no)
				(sheetname "")
			)
			(fill
				(thermal_gap 0.5)
				(thermal_bridge_width 0.5)
				(island_removal_mode 0)
			)
			(polygon
				(pts
					(xy 176.53 -19.939) (xy 176.022 -19.939) (xy 176.022 -19.558) (xy 176.53 -19.558)
				)
			)
		)
		(zone
			(layer "B.Cu")
			(hatch none 0.5)
			(connect_pads
				(clearance 0)
			)
			(min_thickness 0.25)
			(keepout
				(tracks not_allowed)
				(vias allowed)
				(pads allowed)
				(copperpour not_allowed)
				(footprints allowed)
			)
			(placement
				(enabled no)
				(sheetname "")
			)
			(fill
				(thermal_gap 0.5)
				(thermal_bridge_width 0.5)
				(island_removal_mode 0)
			)
			(polygon
				(pts
					(xy 176.53 -19.558) (xy 176.022 -19.558) (xy 176.022 -19.939) (xy 176.53 -19.939)
				)
			)
		)
	)
	(footprint ""
		(layer "B.Cu")
		(at 433.578 -151.257 -90)
		(property "Reference" "R2L15"
			(at 0 0 90)
			(layer "B.SilkS")
			(hide yes)
			(effects
				(font
					(size 1.27 1.27)
				)
				(justify mirror)
			)
		)
		(property "Value" ""
			(at 0 0 90)
			(layer "B.Fab")
			(effects
				(font
					(size 1.27 1.27)
				)
				(justify mirror)
			)
		)
		(duplicate_pad_numbers_are_jumpers no)
		(fp_poly
			(pts
				(xy 0.2794 -0.1016) (xy -0.2794 -0.1016) (xy -0.2794 0.9906) (xy 0.2794 0.9906)
			)
			(stroke
				(width 0)
				(type default)
			)
			(fill no)
			(layer "B.CrtYd")
		)
		(fp_line
			(start -0.2794 0.9906)
			(end -0.2794 -0.1016)
			(stroke
				(width 0.1)
				(type default)
			)
			(layer "B.Fab")
		)
		(fp_line
			(start 0.2794 0.9906)
			(end -0.2794 0.9906)
			(stroke
				(width 0.1)
				(type default)
			)
			(layer "B.Fab")
		)
		(fp_line
			(start -0.2794 -0.1016)
			(end 0.2794 -0.1016)
			(stroke
				(width 0.1)
				(type default)
			)
			(layer "B.Fab")
		)
		(fp_line
			(start 0.2794 -0.1016)
			(end 0.2794 0.9906)
			(stroke
				(width 0.1)
				(type default)
			)
			(layer "B.Fab")
		)
		(pad "1" smd rect
			(at 0 0 90)
			(size 0.508 0.508)
			(layers "B.Cu" "B.Mask" "B.Paste")
			(net "P3V3_STBY")
		)
		(pad "2" smd rect
			(at 0 0.889 90)
			(size 0.508 0.508)
			(layers "B.Cu" "B.Mask" "B.Paste")
			(net "SGPIO_PCH_SATA_DOUT0_R")
		)
		(zone
			(layer "B.Cu")
			(hatch none 0.5)
			(connect_pads
				(clearance 0)
			)
			(min_thickness 0.25)
			(keepout
				(tracks not_allowed)
				(vias allowed)
				(pads allowed)
				(copperpour not_allowed)
				(footprints allowed)
			)
			(placement
				(enabled no)
				(sheetname "")
			)
			(fill
				(thermal_gap 0.5)
				(thermal_bridge_width 0.5)
				(island_removal_mode 0)
			)
			(polygon
				(pts
					(xy 432.943 -151.003) (xy 432.943 -151.511) (xy 433.324 -151.511) (xy 433.324 -151.003)
				)
			)
		)
		(zone
			(layer "B.Cu")
			(hatch none 0.5)
			(connect_pads
				(clearance 0)
			)
			(min_thickness 0.25)
			(keepout
				(tracks allowed)
				(vias not_allowed)
				(pads allowed)
				(copperpour not_allowed)
				(footprints allowed)
			)
			(placement
				(enabled no)
				(sheetname "")
			)
			(fill
				(thermal_gap 0.5)
				(thermal_bridge_width 0.5)
				(island_removal_mode 0)
			)
			(polygon
				(pts
					(xy 433.324 -151.003) (xy 433.324 -151.511) (xy 432.943 -151.511) (xy 432.943 -151.003)
				)
			)
		)
	)
	(footprint ""
		(layer "B.Cu")
		(at 169.545 -65.024)
		(property "Reference" "CF14"
			(at 0 0 0)
			(layer "B.SilkS")
			(hide yes)
			(effects
				(font
					(size 1.27 1.27)
				)
				(justify mirror)
			)
		)
		(property "Value" "*"
			(at -1.1811 -2.8194 0)
			(unlocked yes)
			(layer "B.Fab")
			(hide yes)
			(effects
				(font
					(size 1.27 1.016)
					(thickness 0.1524)
				)
				(justify mirror)
			)
		)
		(property "Device Type" "SC22P50V2JN-4GP_SMD-BCG-SC22P5A"
			(at -1.1811 -4.3434 0)
			(unlocked yes)
			(layer "B.Fab")
			(hide yes)
			(effects
				(font
					(size 1.27 1.016)
					(thickness 0.1524)
				)
				(justify mirror)
			)
		)
		(duplicate_pad_numbers_are_jumpers no)
		(fp_rect
			(start 0.4318 0.9525)
			(end -0.4318 -0.9525)
			(stroke
				(width 0)
				(type default)
			)
			(fill no)
			(layer "B.CrtYd")
		)
		(fp_rect
			(start 0.4318 0.9525)
			(end -0.4318 -0.9525)
			(stroke
				(width 0)
				(type default)
			)
			(fill no)
			(layer "B.Fab")
		)
		(pad "1" smd custom
			(at 0 -0.4445 180)
			(size 0.1524 0.1524)
			(layers "B.Cu" "B.Mask" "B.Paste")
			(net "VR_PVCCIO_CPU1_AIREF1")
			(options
				(clearance outline)
				(anchor circle)
			)
			(primitives
				(gr_poly
					(pts
						(arc
							(start 0.3048 0.2032)
							(mid 0.275042 0.275042)
							(end 0.2032 0.3048)
						)
						(arc
							(start -0.2032 0.3048)
							(mid -0.275042 0.275042)
							(end -0.3048 0.2032)
						)
						(arc
							(start -0.3048 -0.2032)
							(mid -0.275042 -0.275042)
							(end -0.2032 -0.3048)
						)
						(arc
							(start 0.2032 -0.3048)
							(mid 0.275042 -0.275042)
							(end 0.3048 -0.2032)
						)
					)
					(width 0)
					(fill yes)
				)
			)
		)
		(pad "2" smd custom
			(at 0 0.4445 180)
			(size 0.1524 0.1524)
			(layers "B.Cu" "B.Mask" "B.Paste")
			(net "ISENSE_PVCCIO_CPU1_PH1_IMON")
			(options
				(clearance outline)
				(anchor circle)
			)
			(primitives
				(gr_poly
					(pts
						(arc
							(start 0.3048 0.2032)
							(mid 0.275042 0.275042)
							(end 0.2032 0.3048)
						)
						(arc
							(start -0.2032 0.3048)
							(mid -0.275042 0.275042)
							(end -0.3048 0.2032)
						)
						(arc
							(start -0.3048 -0.2032)
							(mid -0.275042 -0.275042)
							(end -0.2032 -0.3048)
						)
						(arc
							(start 0.2032 -0.3048)
							(mid 0.275042 -0.275042)
							(end 0.3048 -0.2032)
						)
					)
					(width 0)
					(fill yes)
				)
			)
		)
	)
	(footprint ""
		(layer "B.Cu")
		(at 349.133414 -125.227842 -90)
		(property "Reference" "R768"
			(at 0.8382 -0.67818 270)
			(unlocked yes)
			(layer "B.SilkS")
			(effects
				(font
					(size 0.4064 0.254)
					(thickness 0.1524)
				)
				(justify left mirror)
			)
		)
		(property "Value" ""
			(at 0 0 90)
			(layer "B.Fab")
			(effects
				(font
					(size 1.27 1.27)
				)
				(justify mirror)
			)
		)
		(duplicate_pad_numbers_are_jumpers no)
		(fp_poly
			(pts
				(xy 0.2794 -0.1016) (xy -0.2794 -0.1016) (xy -0.2794 0.9906) (xy 0.2794 0.9906)
			)
			(stroke
				(width 0)
				(type default)
			)
			(fill no)
			(layer "B.CrtYd")
		)
		(fp_line
			(start -0.2794 0.9906)
			(end -0.2794 -0.1016)
			(stroke
				(width 0.1)
				(type default)
			)
			(layer "B.Fab")
		)
		(fp_line
			(start 0.2794 0.9906)
			(end -0.2794 0.9906)
			(stroke
				(width 0.1)
				(type default)
			)
			(layer "B.Fab")
		)
		(fp_line
			(start -0.2794 -0.1016)
			(end 0.2794 -0.1016)
			(stroke
				(width 0.1)
				(type default)
			)
			(layer "B.Fab")
		)
		(fp_line
			(start 0.2794 -0.1016)
			(end 0.2794 0.9906)
			(stroke
				(width 0.1)
				(type default)
			)
			(layer "B.Fab")
		)
		(pad "1" smd rect
			(at 0 0 90)
			(size 0.508 0.508)
			(layers "B.Cu" "B.Mask" "B.Paste")
			(net "P3E_CPU0_PE1_PCH_RXN<14>")
		)
		(pad "2" smd rect
			(at 0 0.889 90)
			(size 0.508 0.508)
			(layers "B.Cu" "B.Mask" "B.Paste")
			(net "P3E_CPU0_PE1_PCH_CON_RXN<14>")
		)
		(zone
			(layer "B.Cu")
			(hatch none 0.5)
			(connect_pads
				(clearance 0)
			)
			(min_thickness 0.25)
			(keepout
				(tracks not_allowed)
				(vias allowed)
				(pads allowed)
				(copperpour not_allowed)
				(footprints allowed)
			)
			(placement
				(enabled no)
				(sheetname "")
			)
			(fill
				(thermal_gap 0.5)
				(thermal_bridge_width 0.5)
				(island_removal_mode 0)
			)
			(polygon
				(pts
					(xy 348.498414 -124.973842) (xy 348.498414 -125.481842) (xy 348.879414 -125.481842) (xy 348.879414 -124.973842)
				)
			)
		)
		(zone
			(layer "B.Cu")
			(hatch none 0.5)
			(connect_pads
				(clearance 0)
			)
			(min_thickness 0.25)
			(keepout
				(tracks allowed)
				(vias not_allowed)
				(pads allowed)
				(copperpour not_allowed)
				(footprints allowed)
			)
			(placement
				(enabled no)
				(sheetname "")
			)
			(fill
				(thermal_gap 0.5)
				(thermal_bridge_width 0.5)
				(island_removal_mode 0)
			)
			(polygon
				(pts
					(xy 348.879414 -124.973842) (xy 348.879414 -125.481842) (xy 348.498414 -125.481842) (xy 348.498414 -124.973842)
				)
			)
		)
	)
	(footprint ""
		(layer "B.Cu")
		(at 18.4404 -4.445)
		(property "Reference" "C9U9"
			(at -3.60807 0.254 270)
			(unlocked yes)
			(layer "B.SilkS")
			(effects
				(font
					(size 0.7874 0.5842)
					(thickness 0.1524)
				)
				(justify mirror)
			)
		)
		(property "Value" ""
			(at 0 0 0)
			(layer "B.Fab")
			(effects
				(font
					(size 1.27 1.27)
				)
				(justify mirror)
			)
		)
		(duplicate_pad_numbers_are_jumpers no)
		(fp_line
			(start -2.504948 -1.616456)
			(end -2.504948 1.633728)
			(stroke
				(width 0.1524)
				(type default)
			)
			(layer "B.SilkS")
		)
		(fp_line
			(start -2.504948 1.633728)
			(end -1.6002 1.633728)
			(stroke
				(width 0.1524)
				(type default)
			)
			(layer "B.SilkS")
		)
		(fp_line
			(start -2.286 7.366)
			(end -2.286 1.63195)
			(stroke
				(width 0.1524)
				(type default)
			)
			(layer "B.SilkS")
		)
		(fp_line
			(start -2.286 7.366)
			(end -1.600708 7.366)
			(stroke
				(width 0.1524)
				(type default)
			)
			(layer "B.SilkS")
		)
		(fp_line
			(start -1.6002 -1.616456)
			(end -2.504948 -1.616456)
			(stroke
				(width 0.1524)
				(type default)
			)
			(layer "B.SilkS")
		)
		(fp_line
			(start 1.6002 -1.616456)
			(end 2.563114 -1.616456)
			(stroke
				(width 0.1524)
				(type default)
			)
			(layer "B.SilkS")
		)
		(fp_line
			(start 2.286 7.366)
			(end 1.60147 7.366)
			(stroke
				(width 0.1524)
				(type default)
			)
			(layer "B.SilkS")
		)
		(fp_line
			(start 2.286 7.366)
			(end 2.286 1.632712)
			(stroke
				(width 0.1524)
				(type default)
			)
			(layer "B.SilkS")
		)
		(fp_line
			(start 2.563114 -1.616456)
			(end 2.563114 1.633728)
			(stroke
				(width 0.1524)
				(type default)
			)
			(layer "B.SilkS")
		)
		(fp_line
			(start 2.563114 1.633728)
			(end 1.6002 1.633728)
			(stroke
				(width 0.1524)
				(type default)
			)
			(layer "B.SilkS")
		)
		(fp_rect
			(start 2.286 -0.254)
			(end -2.286 7.366)
			(stroke
				(width 0)
				(type default)
			)
			(fill no)
			(layer "B.CrtYd")
		)
		(fp_line
			(start -2.286 -0.254)
			(end -2.286 7.366)
			(stroke
				(width 0.1)
				(type default)
			)
			(layer "B.Fab")
		)
		(fp_line
			(start -2.286 7.366)
			(end 2.286 7.366)
			(stroke
				(width 0.1)
				(type default)
			)
			(layer "B.Fab")
		)
		(fp_line
			(start 2.286 -0.254)
			(end -2.286 -0.254)
			(stroke
				(width 0.1)
				(type default)
			)
			(layer "B.Fab")
		)
		(fp_line
			(start 2.286 7.366)
			(end 2.286 -0.254)
			(stroke
				(width 0.1)
				(type default)
			)
			(layer "B.Fab")
		)
		(pad "1" smd rect
			(at 0 0 180)
			(size 2.54 3.048)
			(layers "B.Cu" "B.Mask" "B.Paste")
			(net "PVDDQ_GHJ")
		)
		(pad "2" smd rect
			(at 0 7.112 180)
			(size 2.54 3.048)
			(layers "B.Cu" "B.Mask" "B.Paste")
			(net "GND")
		)
	)
	(footprint ""
		(layer "B.Cu")
		(at 177.906426 -20.2057 90)
		(property "Reference" "R6T7"
			(at 0 0 90)
			(layer "B.SilkS")
			(hide yes)
			(effects
				(font
					(size 1.27 1.27)
				)
				(justify mirror)
			)
		)
		(property "Value" ""
			(at 0 0 90)
			(layer "B.Fab")
			(effects
				(font
					(size 1.27 1.27)
				)
				(justify mirror)
			)
		)
		(duplicate_pad_numbers_are_jumpers no)
		(fp_poly
			(pts
				(xy 0.2794 -0.1016) (xy -0.2794 -0.1016) (xy -0.2794 0.9906) (xy 0.2794 0.9906)
			)
			(stroke
				(width 0)
				(type default)
			)
			(fill no)
			(layer "B.CrtYd")
		)
		(fp_line
			(start 0.2794 -0.1016)
			(end 0.2794 0.9906)
			(stroke
				(width 0.1)
				(type default)
			)
			(layer "B.Fab")
		)
		(fp_line
			(start -0.2794 -0.1016)
			(end 0.2794 -0.1016)
			(stroke
				(width 0.1)
				(type default)
			)
			(layer "B.Fab")
		)
		(fp_line
			(start 0.2794 0.9906)
			(end -0.2794 0.9906)
			(stroke
				(width 0.1)
				(type default)
			)
			(layer "B.Fab")
		)
		(fp_line
			(start -0.2794 0.9906)
			(end -0.2794 -0.1016)
			(stroke
				(width 0.1)
				(type default)
			)
			(layer "B.Fab")
		)
		(pad "1" smd rect
			(at 0 0 270)
			(size 0.508 0.508)
			(layers "B.Cu" "B.Mask" "B.Paste")
			(net "PVCCIO_CPU1")
		)
		(pad "2" smd rect
			(at 0 0.889 270)
			(size 0.508 0.508)
			(layers "B.Cu" "B.Mask" "B.Paste")
			(net "XDP_CPU1_TDO")
		)
		(zone
			(layer "B.Cu")
			(hatch none 0.5)
			(connect_pads
				(clearance 0)
			)
			(min_thickness 0.25)
			(keepout
				(tracks allowed)
				(vias not_allowed)
				(pads allowed)
				(copperpour not_allowed)
				(footprints allowed)
			)
			(placement
				(enabled no)
				(sheetname "")
			)
			(fill
				(thermal_gap 0.5)
				(thermal_bridge_width 0.5)
				(island_removal_mode 0)
			)
			(polygon
				(pts
					(xy 178.160426 -20.4597) (xy 178.160426 -19.9517) (xy 178.541426 -19.9517) (xy 178.541426 -20.4597)
				)
			)
		)
		(zone
			(layer "B.Cu")
			(hatch none 0.5)
			(connect_pads
				(clearance 0)
			)
			(min_thickness 0.25)
			(keepout
				(tracks not_allowed)
				(vias allowed)
				(pads allowed)
				(copperpour not_allowed)
				(footprints allowed)
			)
			(placement
				(enabled no)
				(sheetname "")
			)
			(fill
				(thermal_gap 0.5)
				(thermal_bridge_width 0.5)
				(island_removal_mode 0)
			)
			(polygon
				(pts
					(xy 178.541426 -20.4597) (xy 178.541426 -19.9517) (xy 178.160426 -19.9517) (xy 178.160426 -20.4597)
				)
			)
		)
	)
	(footprint ""
		(layer "B.Cu")
		(at 370.929916 -37.08654 180)
		(property "Reference" "U7E2"
			(at -3.302 2.274316 0)
			(unlocked yes)
			(layer "B.SilkS")
			(effects
				(font
					(size 0.7874 0.5842)
					(thickness 0.1524)
				)
				(justify left mirror)
			)
		)
		(property "Value" ""
			(at 0 0 0)
			(layer "B.Fab")
			(effects
				(font
					(size 1.27 1.27)
				)
				(justify mirror)
			)
		)
		(duplicate_pad_numbers_are_jumpers no)
		(fp_circle
			(center 0.4699 -0.8382)
			(end 0.3429 -0.8382)
			(stroke
				(width 0.254)
				(type default)
			)
			(fill no)
			(layer "B.SilkS")
		)
		(fp_poly
			(pts
				(xy -0.21463 -0.450088) (xy -1.56337 -0.450088) (xy -1.56337 1.75006) (xy -0.21463 1.75006)
			)
			(stroke
				(width 0)
				(type default)
			)
			(fill no)
			(layer "B.CrtYd")
		)
		(fp_line
			(start -0.21463 1.75006)
			(end -0.21463 -0.450088)
			(stroke
				(width 0.1)
				(type default)
			)
			(layer "B.Fab")
		)
		(fp_line
			(start -0.21463 -0.450088)
			(end -1.56337 -0.450088)
			(stroke
				(width 0.1)
				(type default)
			)
			(layer "B.Fab")
		)
		(fp_line
			(start -1.56337 1.75006)
			(end -0.21463 1.75006)
			(stroke
				(width 0.1)
				(type default)
			)
			(layer "B.Fab")
		)
		(fp_line
			(start -1.56337 -0.450088)
			(end -1.56337 1.75006)
			(stroke
				(width 0.1)
				(type default)
			)
			(layer "B.Fab")
		)
		(fp_circle
			(center 0.4699 -0.8382)
			(end 0.3429 -0.8382)
			(stroke
				(width 0.254)
				(type default)
			)
			(fill no)
			(layer "B.Fab")
		)
		(pad "1" smd rect
			(at 0 0)
			(size 1.016 0.381)
			(layers "B.Cu" "B.Mask" "B.Paste")
			(net "FM_PVCCIN_CPU0_PWR_IN_ALERT_N")
		)
		(pad "2" smd rect
			(at 0 0.649986)
			(size 1.016 0.381)
			(layers "B.Cu" "B.Mask" "B.Paste")
			(net "IRQ_PVCCIN_CPU0_VRHOT_LVC3_N")
		)
		(pad "3" smd rect
			(at 0 1.299972)
			(size 1.016 0.381)
			(layers "B.Cu" "B.Mask" "B.Paste")
			(net "GND")
		)
		(pad "4" smd rect
			(at -1.778 1.299972)
			(size 1.016 0.381)
			(layers "B.Cu" "B.Mask" "B.Paste")
			(net "IRQ_CPU0_PROCHOT_G_N")
		)
		(pad "5" smd rect
			(at -1.778 0)
			(size 1.016 0.381)
			(layers "B.Cu" "B.Mask" "B.Paste")
			(net "P3V3_STBY")
		)
	)
)
